# T6G (Grand Teton) — schematic netlist excerpt (pin names and nets, part order shuffled) for the footprints in the layout excerpt that follows; sources: Cadence DE-HDL packaged netlist, KiCad conversion of 04192023_DAF0TMB3IC0_F0TG_MB_C_brd_V02_OCP.brd

C8070  Q_CAP  1000PF 50V 5% EMPTY  pkg 0402  page 200 : A = PWRGD_PVDDCR_CPU1_P0_R ; B = GND

(kicad_pcb
	(version 20260206)
	(generator "pcbnew")
	(generator_version "10.0")
	(general
		(thickness 1.6)
		(legacy_teardrops no)
	)
	(paper "A4")
	(title_block
		(title "04192023_DAF0TMB3IC0_F0TG_MB_C_brd_V02_OCP.brd")
		(comment 1 "Grand Teton / footprints 2017-2017 of 8354")
	)
	(layers
		(0 "F.Cu" signal "TOP")
		(4 "In1.Cu" signal "GND")
		(6 "In2.Cu" signal "IN1")
		(8 "In3.Cu" signal "GND1")
		(10 "In4.Cu" signal "IN2")
		(12 "In5.Cu" signal "GND2")
		(14 "In6.Cu" signal "IN3")
		(16 "In7.Cu" signal "GND3")
		(18 "In8.Cu" signal "VCC")
		(20 "In9.Cu" signal "VCC1")
		(22 "In10.Cu" signal "GND4")
		(24 "In11.Cu" signal "IN4")
		(26 "In12.Cu" signal "GND5")
		(28 "In13.Cu" signal "IN5")
		(30 "In14.Cu" signal "GND6")
		(32 "In15.Cu" signal "IN6")
		(34 "In16.Cu" signal "GND7")
		(2 "B.Cu" signal "BOTTOM")
		(9 "F.Adhes" user "F.Adhesive")
		(11 "B.Adhes" user "B.Adhesive")
		(13 "F.Paste" user "Package Geometry/Pastemask Top")
		(15 "B.Paste" user "Package Geometry/Pastemask Bottom")
		(5 "F.SilkS" user "Ref Des/Silkscreen Top")
		(7 "B.SilkS" user "Ref Des/Silkscreen Bottom")
		(1 "F.Mask" user "Board Geometry/Soldermask Top")
		(3 "B.Mask" user "Board Geometry/Soldermask Bottom")
		(17 "Dwgs.User" user "User.Drawings")
		(19 "Cmts.User" user "User.Comments")
		(21 "Eco1.User" user "User.Eco1")
		(23 "Eco2.User" user "User.Eco2")
		(25 "Edge.Cuts" user "Board Geometry/Outline")
		(27 "Margin" user)
		(31 "F.CrtYd" user "Package Geometry/Place Bound Top")
		(29 "B.CrtYd" user "Package Geometry/Place Bound Bottom")
		(35 "F.Fab" user "Ref Des/Assembly Top")
		(33 "B.Fab" user "Ref Des/Assembly Bottom")
	)
	(footprint ""
		(layer "F.Cu")
		(at 304.419 -363.982 180)
		(property "Reference" "C8070"
			(at 0 0 180)
			(layer "F.SilkS")
			(hide yes)
			(effects
				(font
					(size 1.27 1.27)
				)
			)
		)
		(property "Value" ""
			(at 0 0 180)
			(layer "F.Fab")
			(effects
				(font
					(size 1.27 1.27)
				)
			)
		)
		(duplicate_pad_numbers_are_jumpers no)
		(fp_line
			(start 0.7874 0.4064)
			(end -0.7874 0.4064)
			(stroke
				(width 0.1524)
				(type default)
			)
			(layer "F.SilkS")
		)
		(fp_line
			(start 0.7874 -0.4064)
			(end 0.7874 0.4064)
			(stroke
				(width 0.1524)
				(type default)
			)
			(layer "F.SilkS")
		)
		(fp_line
			(start -0.7874 0.4064)
			(end -0.7874 -0.4064)
			(stroke
				(width 0.1524)
				(type default)
			)
			(layer "F.SilkS")
		)
		(fp_line
			(start -0.7874 -0.4064)
			(end 0.7874 -0.4064)
			(stroke
				(width 0.1524)
				(type default)
			)
			(layer "F.SilkS")
		)
		(fp_line
			(start 0.67945 0.3048)
			(end 0.120396 0.3048)
			(stroke
				(width 0.1)
				(type default)
			)
			(layer "F.Fab")
		)
		(fp_line
			(start 0.67945 -0.3048)
			(end 0.67945 0.3048)
			(stroke
				(width 0.1)
				(type default)
			)
			(layer "F.Fab")
		)
		(fp_line
			(start 0.12065 -0.2794)
			(end 0.12065 -0.3048)
			(stroke
				(width 0.1)
				(type default)
			)
			(layer "F.Fab")
		)
		(fp_line
			(start 0.12065 -0.3048)
			(end 0.67945 -0.3048)
			(stroke
				(width 0.1)
				(type default)
			)
			(layer "F.Fab")
		)
		(fp_line
			(start 0.120396 0.3048)
			(end 0.120396 0.2794)
			(stroke
				(width 0.1)
				(type default)
			)
			(layer "F.Fab")
		)
		(fp_line
			(start 0.120396 0.2794)
			(end -0.12065 0.2794)
			(stroke
				(width 0.1)
				(type default)
			)
			(layer "F.Fab")
		)
		(fp_line
			(start -0.12065 0.3048)
			(end -0.67945 0.3048)
			(stroke
				(width 0.1)
				(type default)
			)
			(layer "F.Fab")
		)
		(fp_line
			(start -0.12065 0.2794)
			(end -0.12065 0.3048)
			(stroke
				(width 0.1)
				(type default)
			)
			(layer "F.Fab")
		)
		(fp_line
			(start -0.12065 -0.2794)
			(end 0.12065 -0.2794)
			(stroke
				(width 0.1)
				(type default)
			)
			(layer "F.Fab")
		)
		(fp_line
			(start -0.12065 -0.305054)
			(end -0.12065 -0.2794)
			(stroke
				(width 0.1)
				(type default)
			)
			(layer "F.Fab")
		)
		(fp_line
			(start -0.67945 0.3048)
			(end -0.67945 -0.305054)
			(stroke
				(width 0.1)
				(type default)
			)
			(layer "F.Fab")
		)
		(fp_line
			(start -0.67945 -0.305054)
			(end -0.12065 -0.305054)
			(stroke
				(width 0.1)
				(type default)
			)
			(layer "F.Fab")
		)
		(pad "1" smd circle
			(at -0.40005 0 180)
			(size 0 0)
			(layers "F.Cu" "F.Mask" "F.Paste")
			(net "PWRGD_PVDDCR_CPU1_P0_R")
		)
		(pad "2" smd circle
			(at 0.40005 0 180)
			(size 0 0)
			(layers "F.Cu" "F.Mask" "F.Paste")
			(net "GND")
		)
	)
)
